# T6G (Grand Teton) — schematic netlist excerpt (pin names and nets, part order shuffled) for the footprints in the layout excerpt that follows; sources: Cadence DE-HDL packaged netlist, KiCad conversion of 04192023_DAF0TMB3IC0_F0TG_MB_C_brd_V02_OCP.brd

C2276  Q_CAP  22UF 4V 20% X6S  pkg C0402  page 72 : A = PVDDCR_SOC_P1 ; B = GND
C562  Q_CAP  1UF 4V 20% X6S  pkg 0201  page 279 : A = P0V9_CPU0_RT0_2A ; B = GND
PC141_5  Q_CAP  22UF 4V 20% X6S  pkg C0805  page 203 : A = PVDDCR_CPU1_P0 ; B = GND

(kicad_pcb
	(version 20260206)
	(generator "pcbnew")
	(generator_version "10.0")
	(general
		(thickness 1.6)
		(legacy_teardrops no)
	)
	(paper "A4")
	(title_block
		(title "04192023_DAF0TMB3IC0_F0TG_MB_C_brd_V02_OCP.brd")
		(comment 1 "Grand Teton / footprints 6335-6337 of 8354")
	)
	(layers
		(0 "F.Cu" signal "TOP")
		(4 "In1.Cu" signal "GND")
		(6 "In2.Cu" signal "IN1")
		(8 "In3.Cu" signal "GND1")
		(10 "In4.Cu" signal "IN2")
		(12 "In5.Cu" signal "GND2")
		(14 "In6.Cu" signal "IN3")
		(16 "In7.Cu" signal "GND3")
		(18 "In8.Cu" signal "VCC")
		(20 "In9.Cu" signal "VCC1")
		(22 "In10.Cu" signal "GND4")
		(24 "In11.Cu" signal "IN4")
		(26 "In12.Cu" signal "GND5")
		(28 "In13.Cu" signal "IN5")
		(30 "In14.Cu" signal "GND6")
		(32 "In15.Cu" signal "IN6")
		(34 "In16.Cu" signal "GND7")
		(2 "B.Cu" signal "BOTTOM")
		(9 "F.Adhes" user "F.Adhesive")
		(11 "B.Adhes" user "B.Adhesive")
		(13 "F.Paste" user "Package Geometry/Pastemask Top")
		(15 "B.Paste" user "Package Geometry/Pastemask Bottom")
		(5 "F.SilkS" user "Ref Des/Silkscreen Top")
		(7 "B.SilkS" user "Ref Des/Silkscreen Bottom")
		(1 "F.Mask" user "Board Geometry/Soldermask Top")
		(3 "B.Mask" user "Board Geometry/Soldermask Bottom")
		(17 "Dwgs.User" user "User.Drawings")
		(19 "Cmts.User" user "User.Comments")
		(21 "Eco1.User" user "User.Eco1")
		(23 "Eco2.User" user "User.Eco2")
		(25 "Edge.Cuts" user "Board Geometry/Outline")
		(27 "Margin" user)
		(31 "F.CrtYd" user "Package Geometry/Place Bound Top")
		(29 "B.CrtYd" user "Package Geometry/Place Bound Bottom")
		(35 "F.Fab" user "Ref Des/Assembly Top")
		(33 "B.Fab" user "Ref Des/Assembly Bottom")
	)
	(footprint ""
		(layer "B.Cu")
		(at 346.92082 -326.820276 -90)
		(property "Reference" "PC141_5"
			(at 0 0 90)
			(layer "B.SilkS")
			(hide yes)
			(effects
				(font
					(size 1.27 1.27)
				)
				(justify mirror)
			)
		)
		(property "Value" ""
			(at 0 0 90)
			(layer "B.Fab")
			(effects
				(font
					(size 1.27 1.27)
				)
				(justify mirror)
			)
		)
		(duplicate_pad_numbers_are_jumpers no)
		(fp_line
			(start -1.524 0.762)
			(end 1.524 0.762)
			(stroke
				(width 0.1524)
				(type default)
			)
			(layer "B.SilkS")
		)
		(fp_line
			(start 1.524 0.762)
			(end 1.524 -0.762)
			(stroke
				(width 0.1524)
				(type default)
			)
			(layer "B.SilkS")
		)
		(fp_line
			(start -1.524 -0.762)
			(end -1.524 0.762)
			(stroke
				(width 0.1524)
				(type default)
			)
			(layer "B.SilkS")
		)
		(fp_line
			(start 1.524 -0.762)
			(end -1.524 -0.762)
			(stroke
				(width 0.1524)
				(type default)
			)
			(layer "B.SilkS")
		)
		(fp_line
			(start -1.1049 0.724916)
			(end -1.1049 -0.724916)
			(stroke
				(width 0.1)
				(type default)
			)
			(layer "B.Fab")
		)
		(fp_line
			(start 1.1049 0.724916)
			(end -1.1049 0.724916)
			(stroke
				(width 0.1)
				(type default)
			)
			(layer "B.Fab")
		)
		(fp_line
			(start -1.1049 -0.724916)
			(end 1.1049 -0.724916)
			(stroke
				(width 0.1)
				(type default)
			)
			(layer "B.Fab")
		)
		(fp_line
			(start 1.1049 -0.724916)
			(end 1.1049 0.724916)
			(stroke
				(width 0.1)
				(type default)
			)
			(layer "B.Fab")
		)
		(pad "1" smd rect
			(at 0.889 0 270)
			(size 1.016 1.27)
			(layers "B.Cu" "B.Mask" "B.Paste")
			(net "PVDDCR_CPU1_P0")
		)
		(pad "2" smd rect
			(at -0.889 0 270)
			(size 1.016 1.27)
			(layers "B.Cu" "B.Mask" "B.Paste")
			(net "GND")
		)
	)
	(footprint ""
		(layer "B.Cu")
		(at 304.578258 -395.148562 90)
		(property "Reference" "C562"
			(at 0 0 90)
			(layer "B.SilkS")
			(hide yes)
			(effects
				(font
					(size 1.27 1.27)
				)
				(justify mirror)
			)
		)
		(property "Value" ""
			(at 0 0 90)
			(layer "B.Fab")
			(effects
				(font
					(size 1.27 1.27)
				)
				(justify mirror)
			)
		)
		(duplicate_pad_numbers_are_jumpers no)
		(fp_line
			(start 0.299974 -0.150114)
			(end -0.299974 -0.150114)
			(stroke
				(width 0.1)
				(type default)
			)
			(layer "B.Fab")
		)
		(fp_line
			(start -0.299974 -0.150114)
			(end -0.299974 0.150114)
			(stroke
				(width 0.1)
				(type default)
			)
			(layer "B.Fab")
		)
		(fp_line
			(start 0.299974 0.150114)
			(end 0.299974 -0.150114)
			(stroke
				(width 0.1)
				(type default)
			)
			(layer "B.Fab")
		)
		(fp_line
			(start -0.299974 0.150114)
			(end 0.299974 0.150114)
			(stroke
				(width 0.1)
				(type default)
			)
			(layer "B.Fab")
		)
		(pad "1" smd rect
			(at 0.2667 0 270)
			(size 0.3048 0.381)
			(layers "B.Cu" "B.Mask" "B.Paste")
			(net "P0V9_CPU0_RT0_2A")
		)
		(pad "2" smd rect
			(at -0.2667 0 270)
			(size 0.3048 0.381)
			(layers "B.Cu" "B.Mask" "B.Paste")
			(net "GND")
		)
	)
	(footprint ""
		(layer "B.Cu")
		(at 113.105946 -258.795266 180)
		(property "Reference" "C2276"
			(at 0 0 0)
			(layer "B.SilkS")
			(hide yes)
			(effects
				(font
					(size 1.27 1.27)
				)
				(justify mirror)
			)
		)
		(property "Value" ""
			(at 0 0 0)
			(layer "B.Fab")
			(effects
				(font
					(size 1.27 1.27)
				)
				(justify mirror)
			)
		)
		(duplicate_pad_numbers_are_jumpers no)
		(fp_line
			(start 0.7874 0.4064)
			(end 0.7874 -0.4064)
			(stroke
				(width 0.1524)
				(type default)
			)
			(layer "B.SilkS")
		)
		(fp_line
			(start 0.7874 -0.4064)
			(end -0.7874 -0.4064)
			(stroke
				(width 0.1524)
				(type default)
			)
			(layer "B.SilkS")
		)
		(fp_line
			(start -0.7874 0.4064)
			(end 0.7874 0.4064)
			(stroke
				(width 0.1524)
				(type default)
			)
			(layer "B.SilkS")
		)
		(fp_line
			(start -0.7874 -0.4064)
			(end -0.7874 0.4064)
			(stroke
				(width 0.1524)
				(type default)
			)
			(layer "B.SilkS")
		)
		(fp_line
			(start 0.67945 0.3048)
			(end 0.67945 -0.305054)
			(stroke
				(width 0.1)
				(type default)
			)
			(layer "B.Fab")
		)
		(fp_line
			(start 0.67945 -0.305054)
			(end 0.12065 -0.305054)
			(stroke
				(width 0.1)
				(type default)
			)
			(layer "B.Fab")
		)
		(fp_line
			(start 0.12065 0.3048)
			(end 0.67945 0.3048)
			(stroke
				(width 0.1)
				(type default)
			)
			(layer "B.Fab")
		)
		(fp_line
			(start 0.12065 0.2794)
			(end 0.12065 0.3048)
			(stroke
				(width 0.1)
				(type default)
			)
			(layer "B.Fab")
		)
		(fp_line
			(start 0.12065 -0.2794)
			(end -0.12065 -0.2794)
			(stroke
				(width 0.1)
				(type default)
			)
			(layer "B.Fab")
		)
		(fp_line
			(start 0.12065 -0.305054)
			(end 0.12065 -0.2794)
			(stroke
				(width 0.1)
				(type default)
			)
			(layer "B.Fab")
		)
		(fp_line
			(start -0.120396 0.3048)
			(end -0.120396 0.2794)
			(stroke
				(width 0.1)
				(type default)
			)
			(layer "B.Fab")
		)
		(fp_line
			(start -0.120396 0.2794)
			(end 0.12065 0.2794)
			(stroke
				(width 0.1)
				(type default)
			)
			(layer "B.Fab")
		)
		(fp_line
			(start -0.12065 -0.2794)
			(end -0.12065 -0.3048)
			(stroke
				(width 0.1)
				(type default)
			)
			(layer "B.Fab")
		)
		(fp_line
			(start -0.12065 -0.3048)
			(end -0.67945 -0.3048)
			(stroke
				(width 0.1)
				(type default)
			)
			(layer "B.Fab")
		)
		(fp_line
			(start -0.67945 0.3048)
			(end -0.120396 0.3048)
			(stroke
				(width 0.1)
				(type default)
			)
			(layer "B.Fab")
		)
		(fp_line
			(start -0.67945 -0.3048)
			(end -0.67945 0.3048)
			(stroke
				(width 0.1)
				(type default)
			)
			(layer "B.Fab")
		)
		(pad "1" smd circle
			(at 0.40005 0)
			(size 0 0)
			(layers "B.Cu" "B.Mask" "B.Paste")
			(net "PVDDCR_SOC_P1")
		)
		(pad "2" smd circle
			(at -0.40005 0)
			(size 0 0)
			(layers "B.Cu" "B.Mask" "B.Paste")
			(net "GND")
		)
	)
)
